# S9S_MB_2U (Grand Teton) — schematic netlist excerpt (pin names and nets, part order shuffled) for the footprints in the layout excerpt that follows; sources: Cadence DE-HDL packaged netlist, KiCad conversion of 03242023_DA0F0TMBIJ0_F0T_Motherboard_J_brd_V01_OCP.brd

R2736  Q_RES  33.2 1% CHIP  pkg 0402LF  page 114 : A = PWRGD_CHF_CPU1_DIMM2 ; B = PWRGD_FAIL_CPU1_EF
C1393  Q_CAP  47UF 2.5V 20% X6S  pkg C0603  page 78 : A = PVNN_MAIN_CPU1 ; B = GND

(kicad_pcb
	(version 20260206)
	(generator "pcbnew")
	(generator_version "10.0")
	(general
		(thickness 1.6)
		(legacy_teardrops no)
	)
	(paper "A4")
	(title_block
		(title "03242023_DA0F0TMBIJ0_F0T_Motherboard_J_brd_V01_OCP.brd")
		(comment 1 "Grand Teton / footprints 5849-5850 of 6105")
	)
	(layers
		(0 "F.Cu" signal "TOP")
		(4 "In1.Cu" signal "GND")
		(6 "In2.Cu" signal "IN1")
		(8 "In3.Cu" signal "GND1")
		(10 "In4.Cu" signal "IN2")
		(12 "In5.Cu" signal "GND2")
		(14 "In6.Cu" signal "IN3")
		(16 "In7.Cu" signal "GND3")
		(18 "In8.Cu" signal "VCC")
		(20 "In9.Cu" signal "VCC1")
		(22 "In10.Cu" signal "GND4")
		(24 "In11.Cu" signal "IN4")
		(26 "In12.Cu" signal "GND5")
		(28 "In13.Cu" signal "IN5")
		(30 "In14.Cu" signal "GND6")
		(32 "In15.Cu" signal "IN6")
		(34 "In16.Cu" signal "GND7")
		(2 "B.Cu" signal "BOTTOM")
		(9 "F.Adhes" user "F.Adhesive")
		(11 "B.Adhes" user "B.Adhesive")
		(13 "F.Paste" user "Package Geometry/Pastemask Top")
		(15 "B.Paste" user "Package Geometry/Pastemask Bottom")
		(5 "F.SilkS" user "Ref Des/Silkscreen Top")
		(7 "B.SilkS" user "Ref Des/Silkscreen Bottom")
		(1 "F.Mask" user "Board Geometry/Soldermask Top")
		(3 "B.Mask" user "Board Geometry/Soldermask Bottom")
		(17 "Dwgs.User" user "User.Drawings")
		(19 "Cmts.User" user "User.Comments")
		(21 "Eco1.User" user "User.Eco1")
		(23 "Eco2.User" user "User.Eco2")
		(25 "Edge.Cuts" user "Board Geometry/Outline")
		(27 "Margin" user)
		(31 "F.CrtYd" user "Package Geometry/Place Bound Top")
		(29 "B.CrtYd" user "Package Geometry/Place Bound Bottom")
		(35 "F.Fab" user "Ref Des/Assembly Top")
		(33 "B.Fab" user "Ref Des/Assembly Bottom")
	)
	(footprint ""
		(layer "B.Cu")
		(at 178.323748 -319.022476 90)
		(property "Reference" "R2736"
			(at 0 0 90)
			(layer "B.SilkS")
			(hide yes)
			(effects
				(font
					(size 1.27 1.27)
				)
				(justify mirror)
			)
		)
		(property "Value" ""
			(at 0 0 90)
			(layer "B.Fab")
			(effects
				(font
					(size 1.27 1.27)
				)
				(justify mirror)
			)
		)
		(duplicate_pad_numbers_are_jumpers no)
		(fp_line
			(start 0.7874 -0.4064)
			(end -0.7874 -0.4064)
			(stroke
				(width 0.1524)
				(type default)
			)
			(layer "B.SilkS")
		)
		(fp_line
			(start -0.7874 -0.4064)
			(end -0.7874 0.4064)
			(stroke
				(width 0.1524)
				(type default)
			)
			(layer "B.SilkS")
		)
		(fp_line
			(start 0.7874 0.4064)
			(end 0.7874 -0.4064)
			(stroke
				(width 0.1524)
				(type default)
			)
			(layer "B.SilkS")
		)
		(fp_line
			(start -0.7874 0.4064)
			(end 0.7874 0.4064)
			(stroke
				(width 0.1524)
				(type default)
			)
			(layer "B.SilkS")
		)
		(fp_line
			(start 0.67945 -0.305054)
			(end 0.12065 -0.305054)
			(stroke
				(width 0.1)
				(type default)
			)
			(layer "B.Fab")
		)
		(fp_line
			(start 0.12065 -0.305054)
			(end 0.12065 -0.2794)
			(stroke
				(width 0.1)
				(type default)
			)
			(layer "B.Fab")
		)
		(fp_line
			(start -0.12065 -0.3048)
			(end -0.67945 -0.3048)
			(stroke
				(width 0.1)
				(type default)
			)
			(layer "B.Fab")
		)
		(fp_line
			(start -0.67945 -0.3048)
			(end -0.67945 0.3048)
			(stroke
				(width 0.1)
				(type default)
			)
			(layer "B.Fab")
		)
		(fp_line
			(start 0.12065 -0.2794)
			(end -0.12065 -0.2794)
			(stroke
				(width 0.1)
				(type default)
			)
			(layer "B.Fab")
		)
		(fp_line
			(start -0.12065 -0.2794)
			(end -0.12065 -0.3048)
			(stroke
				(width 0.1)
				(type default)
			)
			(layer "B.Fab")
		)
		(fp_line
			(start 0.12065 0.2794)
			(end 0.12065 0.3048)
			(stroke
				(width 0.1)
				(type default)
			)
			(layer "B.Fab")
		)
		(fp_line
			(start -0.120396 0.2794)
			(end 0.12065 0.2794)
			(stroke
				(width 0.1)
				(type default)
			)
			(layer "B.Fab")
		)
		(fp_line
			(start 0.67945 0.3048)
			(end 0.67945 -0.305054)
			(stroke
				(width 0.1)
				(type default)
			)
			(layer "B.Fab")
		)
		(fp_line
			(start 0.12065 0.3048)
			(end 0.67945 0.3048)
			(stroke
				(width 0.1)
				(type default)
			)
			(layer "B.Fab")
		)
		(fp_line
			(start -0.120396 0.3048)
			(end -0.120396 0.2794)
			(stroke
				(width 0.1)
				(type default)
			)
			(layer "B.Fab")
		)
		(fp_line
			(start -0.67945 0.3048)
			(end -0.120396 0.3048)
			(stroke
				(width 0.1)
				(type default)
			)
			(layer "B.Fab")
		)
		(pad "1" smd circle
			(at 0.40005 0 270)
			(size 0 0)
			(layers "B.Cu" "B.Mask" "B.Paste")
			(net "PWRGD_CHF_CPU1_DIMM2")
		)
		(pad "2" smd circle
			(at -0.40005 0 270)
			(size 0 0)
			(layers "B.Cu" "B.Mask" "B.Paste")
			(net "PWRGD_FAIL_CPU1_EF")
		)
	)
	(footprint ""
		(layer "B.Cu")
		(at 104.790494 -237.794292 -90)
		(property "Reference" "C1393"
			(at 0 0 90)
			(layer "B.SilkS")
			(hide yes)
			(effects
				(font
					(size 1.27 1.27)
				)
				(justify mirror)
			)
		)
		(property "Value" ""
			(at 0 0 90)
			(layer "B.Fab")
			(effects
				(font
					(size 1.27 1.27)
				)
				(justify mirror)
			)
		)
		(duplicate_pad_numbers_are_jumpers no)
		(fp_line
			(start -1.2954 0.5842)
			(end 1.2954 0.5842)
			(stroke
				(width 0.1524)
				(type default)
			)
			(layer "B.SilkS")
		)
		(fp_line
			(start 1.2954 0.5842)
			(end 1.2954 -0.5842)
			(stroke
				(width 0.1524)
				(type default)
			)
			(layer "B.SilkS")
		)
		(fp_line
			(start -1.2954 -0.5842)
			(end -1.2954 0.5842)
			(stroke
				(width 0.1524)
				(type default)
			)
			(layer "B.SilkS")
		)
		(fp_line
			(start 0 -0.5842)
			(end 0 0.5842)
			(stroke
				(width 0.1524)
				(type default)
			)
			(layer "B.SilkS")
		)
		(fp_line
			(start 1.2954 -0.5842)
			(end -1.2954 -0.5842)
			(stroke
				(width 0.1524)
				(type default)
			)
			(layer "B.SilkS")
		)
		(fp_line
			(start -0.8636 0.4572)
			(end 0.8636 0.4572)
			(stroke
				(width 0.1)
				(type default)
			)
			(layer "B.Fab")
		)
		(fp_line
			(start 0.8636 0.4572)
			(end 0.8636 0.4064)
			(stroke
				(width 0.1)
				(type default)
			)
			(layer "B.Fab")
		)
		(fp_line
			(start -1.1938 0.4064)
			(end -0.8636 0.4064)
			(stroke
				(width 0.1)
				(type default)
			)
			(layer "B.Fab")
		)
		(fp_line
			(start -0.8636 0.4064)
			(end -0.8636 0.4572)
			(stroke
				(width 0.1)
				(type default)
			)
			(layer "B.Fab")
		)
		(fp_line
			(start 0.8636 0.4064)
			(end 1.1938 0.4064)
			(stroke
				(width 0.1)
				(type default)
			)
			(layer "B.Fab")
		)
		(fp_line
			(start 1.1938 0.4064)
			(end 1.1938 -0.4064)
			(stroke
				(width 0.1)
				(type default)
			)
			(layer "B.Fab")
		)
		(fp_line
			(start -1.1938 -0.4064)
			(end -1.1938 0.4064)
			(stroke
				(width 0.1)
				(type default)
			)
			(layer "B.Fab")
		)
		(fp_line
			(start -0.8636 -0.4064)
			(end -1.1938 -0.4064)
			(stroke
				(width 0.1)
				(type default)
			)
			(layer "B.Fab")
		)
		(fp_line
			(start 0.8636 -0.4064)
			(end 0.8636 -0.4572)
			(stroke
				(width 0.1)
				(type default)
			)
			(layer "B.Fab")
		)
		(fp_line
			(start 1.1938 -0.4064)
			(end 0.8636 -0.4064)
			(stroke
				(width 0.1)
				(type default)
			)
			(layer "B.Fab")
		)
		(fp_line
			(start -0.8636 -0.4572)
			(end -0.8636 -0.4064)
			(stroke
				(width 0.1)
				(type default)
			)
			(layer "B.Fab")
		)
		(fp_line
			(start 0.8636 -0.4572)
			(end -0.8636 -0.4572)
			(stroke
				(width 0.1)
				(type default)
			)
			(layer "B.Fab")
		)
		(pad "1" smd rect
			(at 0.7366 0 180)
			(size 0.7112 0.8128)
			(layers "B.Cu" "B.Mask" "B.Paste")
			(net "PVNN_MAIN_CPU1")
		)
		(pad "2" smd rect
			(at -0.7366 0 180)
			(size 0.7112 0.8128)
			(layers "B.Cu" "B.Mask" "B.Paste")
			(net "GND")
		)
	)
)
